(kicad_pcb
	(version 20260206)
	(generator "pcbnew")
	(generator_version "10.0")
	(general
		(thickness 1.6)
		(legacy_teardrops no)
	)
	(paper "A4")
	(title_block
		(title "04192023_DAF0TMB3IC0_F0TG_MB_C_brd_V02_OCP.brd")
		(comment 1 "Grand Teton / footprints 5076-5082 of 8354")
	)
	(layers
		(0 "F.Cu" signal "TOP")
		(4 "In1.Cu" signal "GND")
		(6 "In2.Cu" signal "IN1")
		(8 "In3.Cu" signal "GND1")
		(10 "In4.Cu" signal "IN2")
		(12 "In5.Cu" signal "GND2")
		(14 "In6.Cu" signal "IN3")
		(16 "In7.Cu" signal "GND3")
		(18 "In8.Cu" signal "VCC")
		(20 "In9.Cu" signal "VCC1")
		(22 "In10.Cu" signal "GND4")
		(24 "In11.Cu" signal "IN4")
		(26 "In12.Cu" signal "GND5")
		(28 "In13.Cu" signal "IN5")
		(30 "In14.Cu" signal "GND6")
		(32 "In15.Cu" signal "IN6")
		(34 "In16.Cu" signal "GND7")
		(2 "B.Cu" signal "BOTTOM")
		(9 "F.Adhes" user "F.Adhesive")
		(11 "B.Adhes" user "B.Adhesive")
		(13 "F.Paste" user "Package Geometry/Pastemask Top")
		(15 "B.Paste" user "Package Geometry/Pastemask Bottom")
		(5 "F.SilkS" user "Ref Des/Silkscreen Top")
		(7 "B.SilkS" user "Ref Des/Silkscreen Bottom")
		(1 "F.Mask" user "Board Geometry/Soldermask Top")
		(3 "B.Mask" user "Board Geometry/Soldermask Bottom")
		(17 "Dwgs.User" user "User.Drawings")
		(19 "Cmts.User" user "User.Comments")
		(21 "Eco1.User" user "User.Eco1")
		(23 "Eco2.User" user "User.Eco2")
		(25 "Edge.Cuts" user "Board Geometry/Outline")
		(27 "Margin" user)
		(31 "F.CrtYd" user "Package Geometry/Place Bound Top")
		(29 "B.CrtYd" user "Package Geometry/Place Bound Bottom")
		(35 "F.Fab" user "Ref Des/Assembly Top")
		(33 "B.Fab" user "Ref Des/Assembly Bottom")
	)
	(footprint ""
		(layer "B.Cu")
		(at 106.891074 -412.028386 90)
		(property "Reference" "C6"
			(at 0 0 90)
			(layer "B.SilkS")
			(hide yes)
			(effects
				(font
					(size 1.27 1.27)
				)
				(justify mirror)
			)
		)
		(property "Value" ""
			(at 0 0 90)
			(layer "B.Fab")
			(effects
				(font
					(size 1.27 1.27)
				)
				(justify mirror)
			)
		)
		(duplicate_pad_numbers_are_jumpers no)
		(fp_line
			(start 0.7874 -0.4064)
			(end -0.7874 -0.4064)
			(stroke
				(width 0.1524)
				(type default)
			)
			(layer "B.SilkS")
		)
		(fp_line
			(start -0.7874 -0.4064)
			(end -0.7874 0.4064)
			(stroke
				(width 0.1524)
				(type default)
			)
			(layer "B.SilkS")
		)
		(fp_line
			(start 0.7874 0.4064)
			(end 0.7874 -0.4064)
			(stroke
				(width 0.1524)
				(type default)
			)
			(layer "B.SilkS")
		)
		(fp_line
			(start -0.7874 0.4064)
			(end 0.7874 0.4064)
			(stroke
				(width 0.1524)
				(type default)
			)
			(layer "B.SilkS")
		)
		(fp_line
			(start 0.67945 -0.305054)
			(end 0.12065 -0.305054)
			(stroke
				(width 0.1)
				(type default)
			)
			(layer "B.Fab")
		)
		(fp_line
			(start 0.12065 -0.305054)
			(end 0.12065 -0.2794)
			(stroke
				(width 0.1)
				(type default)
			)
			(layer "B.Fab")
		)
		(fp_line
			(start -0.12065 -0.3048)
			(end -0.67945 -0.3048)
			(stroke
				(width 0.1)
				(type default)
			)
			(layer "B.Fab")
		)
		(fp_line
			(start -0.67945 -0.3048)
			(end -0.67945 0.3048)
			(stroke
				(width 0.1)
				(type default)
			)
			(layer "B.Fab")
		)
		(fp_line
			(start 0.12065 -0.2794)
			(end -0.12065 -0.2794)
			(stroke
				(width 0.1)
				(type default)
			)
			(layer "B.Fab")
		)
		(fp_line
			(start -0.12065 -0.2794)
			(end -0.12065 -0.3048)
			(stroke
				(width 0.1)
				(type default)
			)
			(layer "B.Fab")
		)
		(fp_line
			(start 0.12065 0.2794)
			(end 0.12065 0.3048)
			(stroke
				(width 0.1)
				(type default)
			)
			(layer "B.Fab")
		)
		(fp_line
			(start -0.120396 0.2794)
			(end 0.12065 0.2794)
			(stroke
				(width 0.1)
				(type default)
			)
			(layer "B.Fab")
		)
		(fp_line
			(start 0.67945 0.3048)
			(end 0.67945 -0.305054)
			(stroke
				(width 0.1)
				(type default)
			)
			(layer "B.Fab")
		)
		(fp_line
			(start 0.12065 0.3048)
			(end 0.67945 0.3048)
			(stroke
				(width 0.1)
				(type default)
			)
			(layer "B.Fab")
		)
		(fp_line
			(start -0.120396 0.3048)
			(end -0.120396 0.2794)
			(stroke
				(width 0.1)
				(type default)
			)
			(layer "B.Fab")
		)
		(fp_line
			(start -0.67945 0.3048)
			(end -0.120396 0.3048)
			(stroke
				(width 0.1)
				(type default)
			)
			(layer "B.Fab")
		)
		(pad "1" smd circle
			(at 0.40005 0 270)
			(size 0 0)
			(layers "B.Cu" "B.Mask" "B.Paste")
			(net "HGX_DETECT_N_ISO")
		)
		(pad "2" smd circle
			(at -0.40005 0 270)
			(size 0 0)
			(layers "B.Cu" "B.Mask" "B.Paste")
			(net "GND")
		)
	)
	(footprint ""
		(layer "B.Cu")
		(at 138.65352 -39.749222 180)
		(property "Reference" "C6059"
			(at 0 0 0)
			(layer "B.SilkS")
			(hide yes)
			(effects
				(font
					(size 1.27 1.27)
				)
				(justify mirror)
			)
		)
		(property "Value" ""
			(at 0 0 0)
			(layer "B.Fab")
			(effects
				(font
					(size 1.27 1.27)
				)
				(justify mirror)
			)
		)
		(duplicate_pad_numbers_are_jumpers no)
		(fp_line
			(start 0.7874 0.4064)
			(end 0.7874 -0.4064)
			(stroke
				(width 0.1524)
				(type default)
			)
			(layer "B.SilkS")
		)
		(fp_line
			(start 0.7874 -0.4064)
			(end -0.7874 -0.4064)
			(stroke
				(width 0.1524)
				(type default)
			)
			(layer "B.SilkS")
		)
		(fp_line
			(start -0.7874 0.4064)
			(end 0.7874 0.4064)
			(stroke
				(width 0.1524)
				(type default)
			)
			(layer "B.SilkS")
		)
		(fp_line
			(start -0.7874 -0.4064)
			(end -0.7874 0.4064)
			(stroke
				(width 0.1524)
				(type default)
			)
			(layer "B.SilkS")
		)
		(fp_line
			(start 0.67945 0.3048)
			(end 0.67945 -0.305054)
			(stroke
				(width 0.1)
				(type default)
			)
			(layer "B.Fab")
		)
		(fp_line
			(start 0.67945 -0.305054)
			(end 0.12065 -0.305054)
			(stroke
				(width 0.1)
				(type default)
			)
			(layer "B.Fab")
		)
		(fp_line
			(start 0.12065 0.3048)
			(end 0.67945 0.3048)
			(stroke
				(width 0.1)
				(type default)
			)
			(layer "B.Fab")
		)
		(fp_line
			(start 0.12065 0.2794)
			(end 0.12065 0.3048)
			(stroke
				(width 0.1)
				(type default)
			)
			(layer "B.Fab")
		)
		(fp_line
			(start 0.12065 -0.2794)
			(end -0.12065 -0.2794)
			(stroke
				(width 0.1)
				(type default)
			)
			(layer "B.Fab")
		)
		(fp_line
			(start 0.12065 -0.305054)
			(end 0.12065 -0.2794)
			(stroke
				(width 0.1)
				(type default)
			)
			(layer "B.Fab")
		)
		(fp_line
			(start -0.120396 0.3048)
			(end -0.120396 0.2794)
			(stroke
				(width 0.1)
				(type default)
			)
			(layer "B.Fab")
		)
		(fp_line
			(start -0.120396 0.2794)
			(end 0.12065 0.2794)
			(stroke
				(width 0.1)
				(type default)
			)
			(layer "B.Fab")
		)
		(fp_line
			(start -0.12065 -0.2794)
			(end -0.12065 -0.3048)
			(stroke
				(width 0.1)
				(type default)
			)
			(layer "B.Fab")
		)
		(fp_line
			(start -0.12065 -0.3048)
			(end -0.67945 -0.3048)
			(stroke
				(width 0.1)
				(type default)
			)
			(layer "B.Fab")
		)
		(fp_line
			(start -0.67945 0.3048)
			(end -0.120396 0.3048)
			(stroke
				(width 0.1)
				(type default)
			)
			(layer "B.Fab")
		)
		(fp_line
			(start -0.67945 -0.3048)
			(end -0.67945 0.3048)
			(stroke
				(width 0.1)
				(type default)
			)
			(layer "B.Fab")
		)
		(pad "1" smd circle
			(at 0.40005 0)
			(size 0 0)
			(layers "B.Cu" "B.Mask" "B.Paste")
			(net "P1V2_AUX")
		)
		(pad "2" smd circle
			(at -0.40005 0)
			(size 0 0)
			(layers "B.Cu" "B.Mask" "B.Paste")
			(net "GND")
		)
	)
	(footprint ""
		(layer "B.Cu")
		(at 412.74619 -396.393162 -90)
		(property "Reference" "C776"
			(at 0 0 90)
			(layer "B.SilkS")
			(hide yes)
			(effects
				(font
					(size 1.27 1.27)
				)
				(justify mirror)
			)
		)
		(property "Value" ""
			(at 0 0 90)
			(layer "B.Fab")
			(effects
				(font
					(size 1.27 1.27)
				)
				(justify mirror)
			)
		)
		(duplicate_pad_numbers_are_jumpers no)
		(fp_line
			(start -0.299974 0.150114)
			(end 0.299974 0.150114)
			(stroke
				(width 0.1)
				(type default)
			)
			(layer "B.Fab")
		)
		(fp_line
			(start 0.299974 0.150114)
			(end 0.299974 -0.150114)
			(stroke
				(width 0.1)
				(type default)
			)
			(layer "B.Fab")
		)
		(fp_line
			(start -0.299974 -0.150114)
			(end -0.299974 0.150114)
			(stroke
				(width 0.1)
				(type default)
			)
			(layer "B.Fab")
		)
		(fp_line
			(start 0.299974 -0.150114)
			(end -0.299974 -0.150114)
			(stroke
				(width 0.1)
				(type default)
			)
			(layer "B.Fab")
		)
		(pad "1" smd rect
			(at 0.2667 0 90)
			(size 0.3048 0.381)
			(layers "B.Cu" "B.Mask" "B.Paste")
			(net "P1V8_CPU0_RT2_1A")
		)
		(pad "2" smd rect
			(at -0.2667 0 90)
			(size 0.3048 0.381)
			(layers "B.Cu" "B.Mask" "B.Paste")
			(net "GND")
		)
	)
	(footprint ""
		(layer "B.Cu")
		(at 365.512858 -397.228568)
		(property "Reference" "C1033"
			(at 0 0 0)
			(layer "B.SilkS")
			(hide yes)
			(effects
				(font
					(size 1.27 1.27)
				)
				(justify mirror)
			)
		)
		(property "Value" ""
			(at 0 0 0)
			(layer "B.Fab")
			(effects
				(font
					(size 1.27 1.27)
				)
				(justify mirror)
			)
		)
		(duplicate_pad_numbers_are_jumpers no)
		(fp_line
			(start -1.524 -0.762)
			(end -1.524 0.762)
			(stroke
				(width 0.1524)
				(type default)
			)
			(layer "B.SilkS")
		)
		(fp_line
			(start -1.524 0.762)
			(end 1.524 0.762)
			(stroke
				(width 0.1524)
				(type default)
			)
			(layer "B.SilkS")
		)
		(fp_line
			(start 1.524 -0.762)
			(end -1.524 -0.762)
			(stroke
				(width 0.1524)
				(type default)
			)
			(layer "B.SilkS")
		)
		(fp_line
			(start 1.524 0.762)
			(end 1.524 -0.762)
			(stroke
				(width 0.1524)
				(type default)
			)
			(layer "B.SilkS")
		)
		(fp_line
			(start -1.1049 -0.724916)
			(end 1.1049 -0.724916)
			(stroke
				(width 0.1)
				(type default)
			)
			(layer "B.Fab")
		)
		(fp_line
			(start -1.1049 0.724916)
			(end -1.1049 -0.724916)
			(stroke
				(width 0.1)
				(type default)
			)
			(layer "B.Fab")
		)
		(fp_line
			(start 1.1049 -0.724916)
			(end 1.1049 0.724916)
			(stroke
				(width 0.1)
				(type default)
			)
			(layer "B.Fab")
		)
		(fp_line
			(start 1.1049 0.724916)
			(end -1.1049 0.724916)
			(stroke
				(width 0.1)
				(type default)
			)
			(layer "B.Fab")
		)
		(pad "1" smd rect
			(at 0.889 0)
			(size 1.016 1.27)
			(layers "B.Cu" "B.Mask" "B.Paste")
			(net "P0V9_CPU0_RT3_2A")
		)
		(pad "2" smd rect
			(at -0.889 0)
			(size 1.016 1.27)
			(layers "B.Cu" "B.Mask" "B.Paste")
			(net "GND")
		)
	)
	(footprint ""
		(layer "B.Cu")
		(at 114.491008 -390.560052 90)
		(property "Reference" "C480"
			(at 0 0 90)
			(layer "B.SilkS")
			(hide yes)
			(effects
				(font
					(size 1.27 1.27)
				)
				(justify mirror)
			)
		)
		(property "Value" ""
			(at 0 0 90)
			(layer "B.Fab")
			(effects
				(font
					(size 1.27 1.27)
				)
				(justify mirror)
			)
		)
		(duplicate_pad_numbers_are_jumpers no)
		(fp_line
			(start 0.7874 -0.4064)
			(end -0.7874 -0.4064)
			(stroke
				(width 0.1524)
				(type default)
			)
			(layer "B.SilkS")
		)
		(fp_line
			(start -0.7874 -0.4064)
			(end -0.7874 0.4064)
			(stroke
				(width 0.1524)
				(type default)
			)
			(layer "B.SilkS")
		)
		(fp_line
			(start 0.7874 0.4064)
			(end 0.7874 -0.4064)
			(stroke
				(width 0.1524)
				(type default)
			)
			(layer "B.SilkS")
		)
		(fp_line
			(start -0.7874 0.4064)
			(end 0.7874 0.4064)
			(stroke
				(width 0.1524)
				(type default)
			)
			(layer "B.SilkS")
		)
		(fp_line
			(start 0.67945 -0.305054)
			(end 0.12065 -0.305054)
			(stroke
				(width 0.1)
				(type default)
			)
			(layer "B.Fab")
		)
		(fp_line
			(start 0.12065 -0.305054)
			(end 0.12065 -0.2794)
			(stroke
				(width 0.1)
				(type default)
			)
			(layer "B.Fab")
		)
		(fp_line
			(start -0.12065 -0.3048)
			(end -0.67945 -0.3048)
			(stroke
				(width 0.1)
				(type default)
			)
			(layer "B.Fab")
		)
		(fp_line
			(start -0.67945 -0.3048)
			(end -0.67945 0.3048)
			(stroke
				(width 0.1)
				(type default)
			)
			(layer "B.Fab")
		)
		(fp_line
			(start 0.12065 -0.2794)
			(end -0.12065 -0.2794)
			(stroke
				(width 0.1)
				(type default)
			)
			(layer "B.Fab")
		)
		(fp_line
			(start -0.12065 -0.2794)
			(end -0.12065 -0.3048)
			(stroke
				(width 0.1)
				(type default)
			)
			(layer "B.Fab")
		)
		(fp_line
			(start 0.12065 0.2794)
			(end 0.12065 0.3048)
			(stroke
				(width 0.1)
				(type default)
			)
			(layer "B.Fab")
		)
		(fp_line
			(start -0.120396 0.2794)
			(end 0.12065 0.2794)
			(stroke
				(width 0.1)
				(type default)
			)
			(layer "B.Fab")
		)
		(fp_line
			(start 0.67945 0.3048)
			(end 0.67945 -0.305054)
			(stroke
				(width 0.1)
				(type default)
			)
			(layer "B.Fab")
		)
		(fp_line
			(start 0.12065 0.3048)
			(end 0.67945 0.3048)
			(stroke
				(width 0.1)
				(type default)
			)
			(layer "B.Fab")
		)
		(fp_line
			(start -0.120396 0.3048)
			(end -0.120396 0.2794)
			(stroke
				(width 0.1)
				(type default)
			)
			(layer "B.Fab")
		)
		(fp_line
			(start -0.67945 0.3048)
			(end -0.120396 0.3048)
			(stroke
				(width 0.1)
				(type default)
			)
			(layer "B.Fab")
		)
		(pad "1" smd circle
			(at 0.40005 0 270)
			(size 0 0)
			(layers "B.Cu" "B.Mask" "B.Paste")
			(net "P0V9_CPU1_RT3_2A")
		)
		(pad "2" smd circle
			(at -0.40005 0 270)
			(size 0 0)
			(layers "B.Cu" "B.Mask" "B.Paste")
			(net "GND")
		)
	)
	(footprint ""
		(layer "B.Cu")
		(at 35.09899 -424.772582)
		(property "Reference" "C1867"
			(at 0 0 0)
			(layer "B.SilkS")
			(hide yes)
			(effects
				(font
					(size 1.27 1.27)
				)
				(justify mirror)
			)
		)
		(property "Value" ""
			(at 0 0 0)
			(layer "B.Fab")
			(effects
				(font
					(size 1.27 1.27)
				)
				(justify mirror)
			)
		)
		(duplicate_pad_numbers_are_jumpers no)
		(fp_line
			(start -1.524 -0.762)
			(end -1.524 0.762)
			(stroke
				(width 0.1524)
				(type default)
			)
			(layer "B.SilkS")
		)
		(fp_line
			(start -1.524 0.762)
			(end 1.524 0.762)
			(stroke
				(width 0.1524)
				(type default)
			)
			(layer "B.SilkS")
		)
		(fp_line
			(start 1.524 -0.762)
			(end -1.524 -0.762)
			(stroke
				(width 0.1524)
				(type default)
			)
			(layer "B.SilkS")
		)
		(fp_line
			(start 1.524 0.762)
			(end 1.524 -0.762)
			(stroke
				(width 0.1524)
				(type default)
			)
			(layer "B.SilkS")
		)
		(fp_line
			(start -1.1049 -0.724916)
			(end 1.1049 -0.724916)
			(stroke
				(width 0.1)
				(type default)
			)
			(layer "B.Fab")
		)
		(fp_line
			(start -1.1049 0.724916)
			(end -1.1049 -0.724916)
			(stroke
				(width 0.1)
				(type default)
			)
			(layer "B.Fab")
		)
		(fp_line
			(start 1.1049 -0.724916)
			(end 1.1049 0.724916)
			(stroke
				(width 0.1)
				(type default)
			)
			(layer "B.Fab")
		)
		(fp_line
			(start 1.1049 0.724916)
			(end -1.1049 0.724916)
			(stroke
				(width 0.1)
				(type default)
			)
			(layer "B.Fab")
		)
		(pad "1" smd rect
			(at 0.889 0)
			(size 1.016 1.27)
			(layers "B.Cu" "B.Mask" "B.Paste")
			(net "P3V3_AUX")
		)
		(pad "2" smd rect
			(at -0.889 0)
			(size 1.016 1.27)
			(layers "B.Cu" "B.Mask" "B.Paste")
			(net "GND")
		)
	)
	(footprint ""
		(layer "B.Cu")
		(at 180.166518 -412.949644 -90)
		(property "Reference" "R2926"
			(at 0 0 90)
			(layer "B.SilkS")
			(hide yes)
			(effects
				(font
					(size 1.27 1.27)
				)
				(justify mirror)
			)
		)
		(property "Value" ""
			(at 0 0 90)
			(layer "B.Fab")
			(effects
				(font
					(size 1.27 1.27)
				)
				(justify mirror)
			)
		)
		(duplicate_pad_numbers_are_jumpers no)
		(fp_line
			(start -0.7874 0.4064)
			(end 0.7874 0.4064)
			(stroke
				(width 0.1524)
				(type default)
			)
			(layer "B.SilkS")
		)
		(fp_line
			(start 0.7874 0.4064)
			(end 0.7874 -0.4064)
			(stroke
				(width 0.1524)
				(type default)
			)
			(layer "B.SilkS")
		)
		(fp_line
			(start -0.7874 -0.4064)
			(end -0.7874 0.4064)
			(stroke
				(width 0.1524)
				(type default)
			)
			(layer "B.SilkS")
		)
		(fp_line
			(start 0.7874 -0.4064)
			(end -0.7874 -0.4064)
			(stroke
				(width 0.1524)
				(type default)
			)
			(layer "B.SilkS")
		)
		(fp_line
			(start -0.67945 0.3048)
			(end -0.120396 0.3048)
			(stroke
				(width 0.1)
				(type default)
			)
			(layer "B.Fab")
		)
		(fp_line
			(start -0.120396 0.3048)
			(end -0.120396 0.2794)
			(stroke
				(width 0.1)
				(type default)
			)
			(layer "B.Fab")
		)
		(fp_line
			(start 0.12065 0.3048)
			(end 0.67945 0.3048)
			(stroke
				(width 0.1)
				(type default)
			)
			(layer "B.Fab")
		)
		(fp_line
			(start 0.67945 0.3048)
			(end 0.67945 -0.305054)
			(stroke
				(width 0.1)
				(type default)
			)
			(layer "B.Fab")
		)
		(fp_line
			(start -0.120396 0.2794)
			(end 0.12065 0.2794)
			(stroke
				(width 0.1)
				(type default)
			)
			(layer "B.Fab")
		)
		(fp_line
			(start 0.12065 0.2794)
			(end 0.12065 0.3048)
			(stroke
				(width 0.1)
				(type default)
			)
			(layer "B.Fab")
		)
		(fp_line
			(start -0.12065 -0.2794)
			(end -0.12065 -0.3048)
			(stroke
				(width 0.1)
				(type default)
			)
			(layer "B.Fab")
		)
		(fp_line
			(start 0.12065 -0.2794)
			(end -0.12065 -0.2794)
			(stroke
				(width 0.1)
				(type default)
			)
			(layer "B.Fab")
		)
		(fp_line
			(start -0.67945 -0.3048)
			(end -0.67945 0.3048)
			(stroke
				(width 0.1)
				(type default)
			)
			(layer "B.Fab")
		)
		(fp_line
			(start -0.12065 -0.3048)
			(end -0.67945 -0.3048)
			(stroke
				(width 0.1)
				(type default)
			)
			(layer "B.Fab")
		)
		(fp_line
			(start 0.12065 -0.305054)
			(end 0.12065 -0.2794)
			(stroke
				(width 0.1)
				(type default)
			)
			(layer "B.Fab")
		)
		(fp_line
			(start 0.67945 -0.305054)
			(end 0.12065 -0.305054)
			(stroke
				(width 0.1)
				(type default)
			)
			(layer "B.Fab")
		)
		(pad "1" smd circle
			(at 0.40005 0 90)
			(size 0 0)
			(layers "B.Cu" "B.Mask" "B.Paste")
			(net "BMC_MONITER_BUF_R")
		)
		(pad "2" smd circle
			(at -0.40005 0 90)
			(size 0 0)
			(layers "B.Cu" "B.Mask" "B.Paste")
			(net "GND")
		)
	)
)
